(kicad_pcb
	(version 20260206)
	(generator "pcbnew")
	(generator_version "10.0")
	(general
		(thickness 1.6)
		(legacy_teardrops no)
	)
	(paper "A4")
	(title_block
		(title "9052_F0T_PDB_Converter_Brick_F_V03_1208_1600_OCP.brd")
		(comment 1 "Grand Teton / footprints 73-78 of 578")
	)
	(layers
		(0 "F.Cu" signal "TOP")
		(4 "In1.Cu" signal "GND")
		(6 "In2.Cu" signal "IN1")
		(8 "In3.Cu" signal "GND1")
		(10 "In4.Cu" signal "VCC")
		(12 "In5.Cu" signal "VCC1")
		(14 "In6.Cu" signal "GND2")
		(16 "In7.Cu" signal "IN2")
		(18 "In8.Cu" signal "GND3")
		(2 "B.Cu" signal "BOTTOM")
		(9 "F.Adhes" user "F.Adhesive")
		(11 "B.Adhes" user "B.Adhesive")
		(13 "F.Paste" user "Package Geometry/Pastemask Top")
		(15 "B.Paste" user "Package Geometry/Pastemask Bottom")
		(5 "F.SilkS" user "Ref Des/Silkscreen Top")
		(7 "B.SilkS" user "Ref Des/Silkscreen Bottom")
		(1 "F.Mask" user "Board Geometry/Soldermask Top")
		(3 "B.Mask" user "Board Geometry/Soldermask Bottom")
		(17 "Dwgs.User" user "User.Drawings")
		(19 "Cmts.User" user "User.Comments")
		(21 "Eco1.User" user "User.Eco1")
		(23 "Eco2.User" user "User.Eco2")
		(25 "Edge.Cuts" user "Board Geometry/Outline")
		(27 "Margin" user)
		(31 "F.CrtYd" user "Package Geometry/Place Bound Top")
		(29 "B.CrtYd" user "Package Geometry/Place Bound Bottom")
		(35 "F.Fab" user "Ref Des/Assembly Top")
		(33 "B.Fab" user "Ref Des/Assembly Bottom")
	)
	(footprint ""
		(layer "F.Cu")
		(at 283.972 -49.276 90)
		(property "Reference" "PR6931"
			(at 0 0 90)
			(layer "F.SilkS")
			(hide yes)
			(effects
				(font
					(size 1.27 1.27)
				)
			)
		)
		(property "Value" ""
			(at 0 0 90)
			(layer "F.Fab")
			(effects
				(font
					(size 1.27 1.27)
				)
			)
		)
		(duplicate_pad_numbers_are_jumpers no)
		(fp_line
			(start 0.7874 -0.4064)
			(end 0.7874 0.4064)
			(stroke
				(width 0.1524)
				(type default)
			)
			(layer "F.SilkS")
		)
		(fp_line
			(start -0.7874 -0.4064)
			(end 0.7874 -0.4064)
			(stroke
				(width 0.1524)
				(type default)
			)
			(layer "F.SilkS")
		)
		(fp_line
			(start 0.7874 0.4064)
			(end -0.7874 0.4064)
			(stroke
				(width 0.1524)
				(type default)
			)
			(layer "F.SilkS")
		)
		(fp_line
			(start -0.7874 0.4064)
			(end -0.7874 -0.4064)
			(stroke
				(width 0.1524)
				(type default)
			)
			(layer "F.SilkS")
		)
		(fp_line
			(start -0.12065 -0.305054)
			(end -0.12065 -0.2794)
			(stroke
				(width 0.1)
				(type default)
			)
			(layer "F.Fab")
		)
		(fp_line
			(start -0.67945 -0.305054)
			(end -0.12065 -0.305054)
			(stroke
				(width 0.1)
				(type default)
			)
			(layer "F.Fab")
		)
		(fp_line
			(start 0.67945 -0.3048)
			(end 0.67945 0.3048)
			(stroke
				(width 0.1)
				(type default)
			)
			(layer "F.Fab")
		)
		(fp_line
			(start 0.12065 -0.3048)
			(end 0.67945 -0.3048)
			(stroke
				(width 0.1)
				(type default)
			)
			(layer "F.Fab")
		)
		(fp_line
			(start 0.12065 -0.2794)
			(end 0.12065 -0.3048)
			(stroke
				(width 0.1)
				(type default)
			)
			(layer "F.Fab")
		)
		(fp_line
			(start -0.12065 -0.2794)
			(end 0.12065 -0.2794)
			(stroke
				(width 0.1)
				(type default)
			)
			(layer "F.Fab")
		)
		(fp_line
			(start 0.120396 0.2794)
			(end -0.12065 0.2794)
			(stroke
				(width 0.1)
				(type default)
			)
			(layer "F.Fab")
		)
		(fp_line
			(start -0.12065 0.2794)
			(end -0.12065 0.3048)
			(stroke
				(width 0.1)
				(type default)
			)
			(layer "F.Fab")
		)
		(fp_line
			(start 0.67945 0.3048)
			(end 0.120396 0.3048)
			(stroke
				(width 0.1)
				(type default)
			)
			(layer "F.Fab")
		)
		(fp_line
			(start 0.120396 0.3048)
			(end 0.120396 0.2794)
			(stroke
				(width 0.1)
				(type default)
			)
			(layer "F.Fab")
		)
		(fp_line
			(start -0.12065 0.3048)
			(end -0.67945 0.3048)
			(stroke
				(width 0.1)
				(type default)
			)
			(layer "F.Fab")
		)
		(fp_line
			(start -0.67945 0.3048)
			(end -0.67945 -0.305054)
			(stroke
				(width 0.1)
				(type default)
			)
			(layer "F.Fab")
		)
		(pad "1" smd circle
			(at -0.40005 0 90)
			(size 0 0)
			(layers "F.Cu" "F.Mask" "F.Paste")
			(net "P52V_HS1_UVH")
		)
		(pad "2" smd circle
			(at 0.40005 0 90)
			(size 0 0)
			(layers "F.Cu" "F.Mask" "F.Paste")
			(net "GND_FIELD_SIGNAL")
		)
	)
	(footprint ""
		(layer "F.Cu")
		(at 217.932 -95.504 -90)
		(property "Reference" "C25"
			(at 0 0 270)
			(layer "F.SilkS")
			(hide yes)
			(effects
				(font
					(size 1.27 1.27)
				)
			)
		)
		(property "Value" ""
			(at 0 0 270)
			(layer "F.Fab")
			(effects
				(font
					(size 1.27 1.27)
				)
			)
		)
		(duplicate_pad_numbers_are_jumpers no)
		(fp_line
			(start -2.2098 0.9398)
			(end -2.2098 -0.9398)
			(stroke
				(width 0.1524)
				(type default)
			)
			(layer "F.SilkS")
		)
		(fp_line
			(start 2.2098 0.9398)
			(end -2.2098 0.9398)
			(stroke
				(width 0.1524)
				(type default)
			)
			(layer "F.SilkS")
		)
		(fp_line
			(start -2.2098 -0.9398)
			(end 2.2098 -0.9398)
			(stroke
				(width 0.1524)
				(type default)
			)
			(layer "F.SilkS")
		)
		(fp_line
			(start 2.2098 -0.9398)
			(end 2.2098 0.9398)
			(stroke
				(width 0.1524)
				(type default)
			)
			(layer "F.SilkS")
		)
		(fp_line
			(start -1.700022 0.899922)
			(end -1.700022 -0.899922)
			(stroke
				(width 0.1)
				(type default)
			)
			(layer "F.Fab")
		)
		(fp_line
			(start 1.700022 0.899922)
			(end -1.700022 0.899922)
			(stroke
				(width 0.1)
				(type default)
			)
			(layer "F.Fab")
		)
		(fp_line
			(start -1.700022 -0.899922)
			(end 1.700022 -0.899922)
			(stroke
				(width 0.1)
				(type default)
			)
			(layer "F.Fab")
		)
		(fp_line
			(start 1.700022 -0.899922)
			(end 1.700022 0.899922)
			(stroke
				(width 0.1)
				(type default)
			)
			(layer "F.Fab")
		)
		(pad "1" smd rect
			(at -1.4732 0 90)
			(size 1.1684 1.5748)
			(layers "F.Cu" "F.Mask" "F.Paste")
			(net "P52V_HS")
		)
		(pad "2" smd rect
			(at 1.4732 0 90)
			(size 1.1684 1.5748)
			(layers "F.Cu" "F.Mask" "F.Paste")
			(net "GND")
		)
	)
	(footprint ""
		(layer "F.Cu")
		(at 168.0464 -12.4968 90)
		(property "Reference" "PC567"
			(at 0 0 90)
			(layer "F.SilkS")
			(hide yes)
			(effects
				(font
					(size 1.27 1.27)
				)
			)
		)
		(property "Value" ""
			(at 0 0 90)
			(layer "F.Fab")
			(effects
				(font
					(size 1.27 1.27)
				)
			)
		)
		(duplicate_pad_numbers_are_jumpers no)
		(fp_line
			(start 1.524 -0.762)
			(end 1.524 0.762)
			(stroke
				(width 0.1524)
				(type default)
			)
			(layer "F.SilkS")
		)
		(fp_line
			(start -1.524 -0.762)
			(end 1.524 -0.762)
			(stroke
				(width 0.1524)
				(type default)
			)
			(layer "F.SilkS")
		)
		(fp_line
			(start 1.524 0.762)
			(end -1.524 0.762)
			(stroke
				(width 0.1524)
				(type default)
			)
			(layer "F.SilkS")
		)
		(fp_line
			(start -1.524 0.762)
			(end -1.524 -0.762)
			(stroke
				(width 0.1524)
				(type default)
			)
			(layer "F.SilkS")
		)
		(fp_line
			(start 1.1049 -0.724916)
			(end -1.1049 -0.724916)
			(stroke
				(width 0.1)
				(type default)
			)
			(layer "F.Fab")
		)
		(fp_line
			(start -1.1049 -0.724916)
			(end -1.1049 0.724916)
			(stroke
				(width 0.1)
				(type default)
			)
			(layer "F.Fab")
		)
		(fp_line
			(start 1.1049 0.724916)
			(end 1.1049 -0.724916)
			(stroke
				(width 0.1)
				(type default)
			)
			(layer "F.Fab")
		)
		(fp_line
			(start -1.1049 0.724916)
			(end 1.1049 0.724916)
			(stroke
				(width 0.1)
				(type default)
			)
			(layer "F.Fab")
		)
		(pad "1" smd rect
			(at -0.889 0 270)
			(size 1.016 1.27)
			(layers "F.Cu" "F.Mask" "F.Paste")
			(net "SW_P12V_FILT__P3V3_AUX")
		)
		(pad "2" smd rect
			(at 0.889 0 270)
			(size 1.016 1.27)
			(layers "F.Cu" "F.Mask" "F.Paste")
			(net "GND")
		)
	)
	(footprint ""
		(layer "F.Cu")
		(at 179.065174 -62.992)
		(property "Reference" "PC122"
			(at 0 0 0)
			(layer "F.SilkS")
			(hide yes)
			(effects
				(font
					(size 1.27 1.27)
				)
			)
		)
		(property "Value" ""
			(at 0 0 0)
			(layer "F.Fab")
			(effects
				(font
					(size 1.27 1.27)
				)
			)
		)
		(duplicate_pad_numbers_are_jumpers no)
		(fp_line
			(start -0.7874 -0.4064)
			(end 0.7874 -0.4064)
			(stroke
				(width 0.1524)
				(type default)
			)
			(layer "F.SilkS")
		)
		(fp_line
			(start -0.7874 0.4064)
			(end -0.7874 -0.4064)
			(stroke
				(width 0.1524)
				(type default)
			)
			(layer "F.SilkS")
		)
		(fp_line
			(start 0.7874 -0.4064)
			(end 0.7874 0.4064)
			(stroke
				(width 0.1524)
				(type default)
			)
			(layer "F.SilkS")
		)
		(fp_line
			(start 0.7874 0.4064)
			(end -0.7874 0.4064)
			(stroke
				(width 0.1524)
				(type default)
			)
			(layer "F.SilkS")
		)
		(fp_line
			(start -0.6858 -0.3048)
			(end -0.1016 -0.3048)
			(stroke
				(width 0.1)
				(type default)
			)
			(layer "F.Fab")
		)
		(fp_line
			(start -0.6858 0.3048)
			(end -0.6858 -0.3048)
			(stroke
				(width 0.1)
				(type default)
			)
			(layer "F.Fab")
		)
		(fp_line
			(start -0.1016 -0.3048)
			(end -0.1016 -0.2794)
			(stroke
				(width 0.1)
				(type default)
			)
			(layer "F.Fab")
		)
		(fp_line
			(start -0.1016 -0.2794)
			(end 0.1016 -0.2794)
			(stroke
				(width 0.1)
				(type default)
			)
			(layer "F.Fab")
		)
		(fp_line
			(start -0.1016 0.2794)
			(end -0.1016 0.3048)
			(stroke
				(width 0.1)
				(type default)
			)
			(layer "F.Fab")
		)
		(fp_line
			(start -0.1016 0.3048)
			(end -0.6858 0.3048)
			(stroke
				(width 0.1)
				(type default)
			)
			(layer "F.Fab")
		)
		(fp_line
			(start 0.1016 -0.3048)
			(end 0.6858 -0.3048)
			(stroke
				(width 0.1)
				(type default)
			)
			(layer "F.Fab")
		)
		(fp_line
			(start 0.1016 -0.2794)
			(end 0.1016 -0.3048)
			(stroke
				(width 0.1)
				(type default)
			)
			(layer "F.Fab")
		)
		(fp_line
			(start 0.1016 0.2794)
			(end -0.1016 0.2794)
			(stroke
				(width 0.1)
				(type default)
			)
			(layer "F.Fab")
		)
		(fp_line
			(start 0.1016 0.3048)
			(end 0.1016 0.2794)
			(stroke
				(width 0.1)
				(type default)
			)
			(layer "F.Fab")
		)
		(fp_line
			(start 0.6858 -0.3048)
			(end 0.6858 0.3048)
			(stroke
				(width 0.1)
				(type default)
			)
			(layer "F.Fab")
		)
		(fp_line
			(start 0.6858 0.3048)
			(end 0.1016 0.3048)
			(stroke
				(width 0.1)
				(type default)
			)
			(layer "F.Fab")
		)
		(pad "1" smd rect
			(at -0.40005 0 180)
			(size 0.4572 0.508)
			(layers "F.Cu" "F.Mask" "F.Paste")
			(net "P12V_BRICK")
		)
		(pad "2" smd rect
			(at 0.40005 0 180)
			(size 0.4572 0.508)
			(layers "F.Cu" "F.Mask" "F.Paste")
			(net "GND")
		)
	)
	(footprint ""
		(layer "F.Cu")
		(at 272.936716 -41.342818 -90)
		(property "Reference" "U29"
			(at -2.916682 -2.083054 90)
			(unlocked yes)
			(layer "F.SilkS")
			(effects
				(font
					(size 0.7874 0.5842)
					(thickness 0.1524)
				)
				(justify left)
			)
		)
		(property "Value" ""
			(at 0 0 270)
			(layer "F.Fab")
			(effects
				(font
					(size 1.27 1.27)
				)
			)
		)
		(duplicate_pad_numbers_are_jumpers no)
		(fp_line
			(start -2.249932 1.549908)
			(end 2.249932 1.549908)
			(stroke
				(width 0.1524)
				(type default)
			)
			(layer "F.SilkS")
		)
		(fp_line
			(start 2.249932 1.549908)
			(end 2.249932 -1.549908)
			(stroke
				(width 0.1524)
				(type default)
			)
			(layer "F.SilkS")
		)
		(fp_line
			(start 0 -0.8128)
			(end -0.737108 -1.549908)
			(stroke
				(width 0.1524)
				(type default)
			)
			(layer "F.SilkS")
		)
		(fp_line
			(start -2.249932 -1.549908)
			(end -2.249932 1.549908)
			(stroke
				(width 0.1524)
				(type default)
			)
			(layer "F.SilkS")
		)
		(fp_line
			(start -0.737108 -1.549908)
			(end -2.249932 -1.549908)
			(stroke
				(width 0.1524)
				(type default)
			)
			(layer "F.SilkS")
		)
		(fp_line
			(start 0.737108 -1.549908)
			(end 0 -0.8128)
			(stroke
				(width 0.1524)
				(type default)
			)
			(layer "F.SilkS")
		)
		(fp_line
			(start 2.249932 -1.549908)
			(end 0.737108 -1.549908)
			(stroke
				(width 0.1524)
				(type default)
			)
			(layer "F.SilkS")
		)
		(fp_poly
			(pts
				(xy -4.7498 -0.467106) (xy -4.7498 -1.483106) (xy -3.7338 -0.975106)
			)
			(stroke
				(width 0)
				(type default)
			)
			(fill yes)
			(layer "F.SilkS")
		)
		(fp_line
			(start -2.249932 1.549908)
			(end 2.249932 1.549908)
			(stroke
				(width 0.1)
				(type default)
			)
			(layer "F.Fab")
		)
		(fp_line
			(start 2.249932 1.549908)
			(end 2.249932 -1.549908)
			(stroke
				(width 0.1)
				(type default)
			)
			(layer "F.Fab")
		)
		(fp_line
			(start -2.249932 -1.549908)
			(end -2.249932 1.549908)
			(stroke
				(width 0.1)
				(type default)
			)
			(layer "F.Fab")
		)
		(fp_line
			(start 2.249932 -1.549908)
			(end -2.249932 -1.549908)
			(stroke
				(width 0.1)
				(type default)
			)
			(layer "F.Fab")
		)
		(fp_poly
			(pts
				(xy -4.7498 -0.467106) (xy -4.7498 -1.483106) (xy -3.7338 -0.975106)
			)
			(stroke
				(width 0)
				(type default)
			)
			(fill yes)
			(layer "F.Fab")
		)
		(pad "1" smd rect
			(at -3.052572 -0.975106 180)
			(size 0.381 1.1684)
			(layers "F.Cu" "F.Mask" "F.Paste")
			(net "P52V_HS1_CS")
		)
		(pad "2" smd rect
			(at -3.052572 -0.32512 180)
			(size 0.381 1.1684)
			(layers "F.Cu" "F.Mask" "F.Paste")
			(net "P52V_HS1_SIO")
		)
		(pad "3" smd rect
			(at -3.052572 0.32512 180)
			(size 0.381 1.1684)
			(layers "F.Cu" "F.Mask" "F.Paste")
			(net "P52V_HS1_DVCC")
		)
		(pad "4" smd rect
			(at -3.052572 0.975106 180)
			(size 0.381 1.1684)
			(layers "F.Cu" "F.Mask" "F.Paste")
			(net "GND")
		)
		(pad "5" smd rect
			(at 3.052572 0.975106 180)
			(size 0.381 1.1684)
			(layers "F.Cu" "F.Mask" "F.Paste")
			(net "P52V_HS1_SIO")
		)
		(pad "6" smd rect
			(at 3.052572 0.32512 180)
			(size 0.381 1.1684)
			(layers "F.Cu" "F.Mask" "F.Paste")
			(net "P52V_HS1_SCK")
		)
		(pad "7" smd rect
			(at 3.052572 -0.32512 180)
			(size 0.381 1.1684)
			(layers "F.Cu" "F.Mask" "F.Paste")
			(net "P52V_HS1_DVCC")
		)
		(pad "8" smd rect
			(at 3.052572 -0.975106 180)
			(size 0.381 1.1684)
			(layers "F.Cu" "F.Mask" "F.Paste")
			(net "P52V_HS1_DVCC")
		)
	)
	(footprint ""
		(layer "F.Cu")
		(at 42.17416 -61.93282 -90)
		(property "Reference" "R5891"
			(at 0 0 270)
			(layer "F.SilkS")
			(hide yes)
			(effects
				(font
					(size 1.27 1.27)
				)
			)
		)
		(property "Value" ""
			(at 0 0 270)
			(layer "F.Fab")
			(effects
				(font
					(size 1.27 1.27)
				)
			)
		)
		(duplicate_pad_numbers_are_jumpers no)
		(fp_line
			(start -0.7874 0.4064)
			(end -0.7874 -0.4064)
			(stroke
				(width 0.1524)
				(type default)
			)
			(layer "F.SilkS")
		)
		(fp_line
			(start 0.7874 0.4064)
			(end -0.7874 0.4064)
			(stroke
				(width 0.1524)
				(type default)
			)
			(layer "F.SilkS")
		)
		(fp_line
			(start -0.7874 -0.4064)
			(end 0.7874 -0.4064)
			(stroke
				(width 0.1524)
				(type default)
			)
			(layer "F.SilkS")
		)
		(fp_line
			(start 0.7874 -0.4064)
			(end 0.7874 0.4064)
			(stroke
				(width 0.1524)
				(type default)
			)
			(layer "F.SilkS")
		)
		(fp_line
			(start -0.67945 0.3048)
			(end -0.67945 -0.305054)
			(stroke
				(width 0.1)
				(type default)
			)
			(layer "F.Fab")
		)
		(fp_line
			(start -0.12065 0.3048)
			(end -0.67945 0.3048)
			(stroke
				(width 0.1)
				(type default)
			)
			(layer "F.Fab")
		)
		(fp_line
			(start 0.120396 0.3048)
			(end 0.120396 0.2794)
			(stroke
				(width 0.1)
				(type default)
			)
			(layer "F.Fab")
		)
		(fp_line
			(start 0.67945 0.3048)
			(end 0.120396 0.3048)
			(stroke
				(width 0.1)
				(type default)
			)
			(layer "F.Fab")
		)
		(fp_line
			(start -0.12065 0.2794)
			(end -0.12065 0.3048)
			(stroke
				(width 0.1)
				(type default)
			)
			(layer "F.Fab")
		)
		(fp_line
			(start 0.120396 0.2794)
			(end -0.12065 0.2794)
			(stroke
				(width 0.1)
				(type default)
			)
			(layer "F.Fab")
		)
		(fp_line
			(start -0.12065 -0.2794)
			(end 0.12065 -0.2794)
			(stroke
				(width 0.1)
				(type default)
			)
			(layer "F.Fab")
		)
		(fp_line
			(start 0.12065 -0.2794)
			(end 0.12065 -0.3048)
			(stroke
				(width 0.1)
				(type default)
			)
			(layer "F.Fab")
		)
		(fp_line
			(start 0.12065 -0.3048)
			(end 0.67945 -0.3048)
			(stroke
				(width 0.1)
				(type default)
			)
			(layer "F.Fab")
		)
		(fp_line
			(start 0.67945 -0.3048)
			(end 0.67945 0.3048)
			(stroke
				(width 0.1)
				(type default)
			)
			(layer "F.Fab")
		)
		(fp_line
			(start -0.67945 -0.305054)
			(end -0.12065 -0.305054)
			(stroke
				(width 0.1)
				(type default)
			)
			(layer "F.Fab")
		)
		(fp_line
			(start -0.12065 -0.305054)
			(end -0.12065 -0.2794)
			(stroke
				(width 0.1)
				(type default)
			)
			(layer "F.Fab")
		)
		(pad "1" smd circle
			(at -0.40005 0 270)
			(size 0 0)
			(layers "F.Cu" "F.Mask" "F.Paste")
			(net "P3V3_AUX")
		)
		(pad "2" smd circle
			(at 0.40005 0 270)
			(size 0 0)
			(layers "F.Cu" "F.Mask" "F.Paste")
			(net "P12V_HPDB_PWRGD")
		)
	)
)
